(kicad_pcb
	(version 20260206)
	(generator "pcbnew")
	(generator_version "10.0")
	(general
		(thickness 1.6)
		(legacy_teardrops no)
	)
	(paper "A4")
	(title_block
		(title "01162023_DA0F0TEBIF0_F0T_Expander_BD_F_brd_V02_OCP.brd")
		(comment 1 "Grand Teton / footprints 4530-4535 of 9728")
	)
	(layers
		(0 "F.Cu" signal "TOP")
		(4 "In1.Cu" signal "GND")
		(6 "In2.Cu" signal "VCC")
		(8 "In3.Cu" signal "VCC1")
		(10 "In4.Cu" signal "GND1")
		(12 "In5.Cu" signal "IN1")
		(14 "In6.Cu" signal "GND2")
		(16 "In7.Cu" signal "IN2")
		(18 "In8.Cu" signal "GND3")
		(20 "In9.Cu" signal "IN3")
		(22 "In10.Cu" signal "GND4")
		(24 "In11.Cu" signal "IN4")
		(26 "In12.Cu" signal "GND5")
		(28 "In13.Cu" signal "IN5")
		(30 "In14.Cu" signal "GND6")
		(32 "In15.Cu" signal "IN6")
		(34 "In16.Cu" signal "GND7")
		(2 "B.Cu" signal "BOTTOM")
		(9 "F.Adhes" user "F.Adhesive")
		(11 "B.Adhes" user "B.Adhesive")
		(13 "F.Paste" user "Package Geometry/Pastemask Top")
		(15 "B.Paste" user "Package Geometry/Pastemask Bottom")
		(5 "F.SilkS" user "Ref Des/Silkscreen Top")
		(7 "B.SilkS" user "Ref Des/Silkscreen Bottom")
		(1 "F.Mask" user "Board Geometry/Soldermask Top")
		(3 "B.Mask" user "Board Geometry/Soldermask Bottom")
		(17 "Dwgs.User" user "User.Drawings")
		(19 "Cmts.User" user "User.Comments")
		(21 "Eco1.User" user "User.Eco1")
		(23 "Eco2.User" user "User.Eco2")
		(25 "Edge.Cuts" user "Board Geometry/Outline")
		(27 "Margin" user)
		(31 "F.CrtYd" user "Package Geometry/Place Bound Top")
		(29 "B.CrtYd" user "Package Geometry/Place Bound Bottom")
		(35 "F.Fab" user "Ref Des/Assembly Top")
		(33 "B.Fab" user "Ref Des/Assembly Bottom")
	)
	(footprint ""
		(layer "F.Cu")
		(at 147.258532 -386.64261 90)
		(property "Reference" "C4104"
			(at 0 0 90)
			(layer "F.SilkS")
			(hide yes)
			(effects
				(font
					(size 1.27 1.27)
				)
			)
		)
		(property "Value" ""
			(at 0 0 90)
			(layer "F.Fab")
			(effects
				(font
					(size 1.27 1.27)
				)
			)
		)
		(duplicate_pad_numbers_are_jumpers no)
		(fp_line
			(start 0.7874 -0.4064)
			(end 0.7874 0.4064)
			(stroke
				(width 0.1524)
				(type default)
			)
			(layer "F.SilkS")
		)
		(fp_line
			(start -0.7874 -0.4064)
			(end 0.7874 -0.4064)
			(stroke
				(width 0.1524)
				(type default)
			)
			(layer "F.SilkS")
		)
		(fp_line
			(start 0.7874 0.4064)
			(end -0.7874 0.4064)
			(stroke
				(width 0.1524)
				(type default)
			)
			(layer "F.SilkS")
		)
		(fp_line
			(start -0.7874 0.4064)
			(end -0.7874 -0.4064)
			(stroke
				(width 0.1524)
				(type default)
			)
			(layer "F.SilkS")
		)
		(fp_line
			(start -0.12065 -0.305054)
			(end -0.12065 -0.2794)
			(stroke
				(width 0.1)
				(type default)
			)
			(layer "F.Fab")
		)
		(fp_line
			(start -0.67945 -0.305054)
			(end -0.12065 -0.305054)
			(stroke
				(width 0.1)
				(type default)
			)
			(layer "F.Fab")
		)
		(fp_line
			(start 0.67945 -0.3048)
			(end 0.67945 0.3048)
			(stroke
				(width 0.1)
				(type default)
			)
			(layer "F.Fab")
		)
		(fp_line
			(start 0.12065 -0.3048)
			(end 0.67945 -0.3048)
			(stroke
				(width 0.1)
				(type default)
			)
			(layer "F.Fab")
		)
		(fp_line
			(start 0.12065 -0.2794)
			(end 0.12065 -0.3048)
			(stroke
				(width 0.1)
				(type default)
			)
			(layer "F.Fab")
		)
		(fp_line
			(start -0.12065 -0.2794)
			(end 0.12065 -0.2794)
			(stroke
				(width 0.1)
				(type default)
			)
			(layer "F.Fab")
		)
		(fp_line
			(start 0.120396 0.2794)
			(end -0.12065 0.2794)
			(stroke
				(width 0.1)
				(type default)
			)
			(layer "F.Fab")
		)
		(fp_line
			(start -0.12065 0.2794)
			(end -0.12065 0.3048)
			(stroke
				(width 0.1)
				(type default)
			)
			(layer "F.Fab")
		)
		(fp_line
			(start 0.67945 0.3048)
			(end 0.120396 0.3048)
			(stroke
				(width 0.1)
				(type default)
			)
			(layer "F.Fab")
		)
		(fp_line
			(start 0.120396 0.3048)
			(end 0.120396 0.2794)
			(stroke
				(width 0.1)
				(type default)
			)
			(layer "F.Fab")
		)
		(fp_line
			(start -0.12065 0.3048)
			(end -0.67945 0.3048)
			(stroke
				(width 0.1)
				(type default)
			)
			(layer "F.Fab")
		)
		(fp_line
			(start -0.67945 0.3048)
			(end -0.67945 -0.305054)
			(stroke
				(width 0.1)
				(type default)
			)
			(layer "F.Fab")
		)
		(pad "1" smd circle
			(at -0.40005 0 90)
			(size 0 0)
			(layers "F.Cu" "F.Mask" "F.Paste")
			(net "GND")
		)
		(pad "2" smd circle
			(at 0.40005 0 90)
			(size 0 0)
			(layers "F.Cu" "F.Mask" "F.Paste")
			(net "SMB_GPU2_ALERT_N")
		)
	)
	(footprint ""
		(layer "F.Cu")
		(at 166.330884 -195.868798)
		(property "Reference" "R3404"
			(at 0 0 0)
			(layer "F.SilkS")
			(hide yes)
			(effects
				(font
					(size 1.27 1.27)
				)
			)
		)
		(property "Value" ""
			(at 0 0 0)
			(layer "F.Fab")
			(effects
				(font
					(size 1.27 1.27)
				)
			)
		)
		(duplicate_pad_numbers_are_jumpers no)
		(fp_line
			(start -0.7874 -0.4064)
			(end 0.7874 -0.4064)
			(stroke
				(width 0.1524)
				(type default)
			)
			(layer "F.SilkS")
		)
		(fp_line
			(start -0.7874 0.4064)
			(end -0.7874 -0.4064)
			(stroke
				(width 0.1524)
				(type default)
			)
			(layer "F.SilkS")
		)
		(fp_line
			(start 0.7874 -0.4064)
			(end 0.7874 0.4064)
			(stroke
				(width 0.1524)
				(type default)
			)
			(layer "F.SilkS")
		)
		(fp_line
			(start 0.7874 0.4064)
			(end -0.7874 0.4064)
			(stroke
				(width 0.1524)
				(type default)
			)
			(layer "F.SilkS")
		)
		(fp_line
			(start -0.67945 -0.305054)
			(end -0.12065 -0.305054)
			(stroke
				(width 0.1)
				(type default)
			)
			(layer "F.Fab")
		)
		(fp_line
			(start -0.67945 0.3048)
			(end -0.67945 -0.305054)
			(stroke
				(width 0.1)
				(type default)
			)
			(layer "F.Fab")
		)
		(fp_line
			(start -0.12065 -0.305054)
			(end -0.12065 -0.2794)
			(stroke
				(width 0.1)
				(type default)
			)
			(layer "F.Fab")
		)
		(fp_line
			(start -0.12065 -0.2794)
			(end 0.12065 -0.2794)
			(stroke
				(width 0.1)
				(type default)
			)
			(layer "F.Fab")
		)
		(fp_line
			(start -0.12065 0.2794)
			(end -0.12065 0.3048)
			(stroke
				(width 0.1)
				(type default)
			)
			(layer "F.Fab")
		)
		(fp_line
			(start -0.12065 0.3048)
			(end -0.67945 0.3048)
			(stroke
				(width 0.1)
				(type default)
			)
			(layer "F.Fab")
		)
		(fp_line
			(start 0.120396 0.2794)
			(end -0.12065 0.2794)
			(stroke
				(width 0.1)
				(type default)
			)
			(layer "F.Fab")
		)
		(fp_line
			(start 0.120396 0.3048)
			(end 0.120396 0.2794)
			(stroke
				(width 0.1)
				(type default)
			)
			(layer "F.Fab")
		)
		(fp_line
			(start 0.12065 -0.3048)
			(end 0.67945 -0.3048)
			(stroke
				(width 0.1)
				(type default)
			)
			(layer "F.Fab")
		)
		(fp_line
			(start 0.12065 -0.2794)
			(end 0.12065 -0.3048)
			(stroke
				(width 0.1)
				(type default)
			)
			(layer "F.Fab")
		)
		(fp_line
			(start 0.67945 -0.3048)
			(end 0.67945 0.3048)
			(stroke
				(width 0.1)
				(type default)
			)
			(layer "F.Fab")
		)
		(fp_line
			(start 0.67945 0.3048)
			(end 0.120396 0.3048)
			(stroke
				(width 0.1)
				(type default)
			)
			(layer "F.Fab")
		)
		(pad "1" smd circle
			(at -0.40005 0)
			(size 0 0)
			(layers "F.Cu" "F.Mask" "F.Paste")
			(net "SPI_BIC1_MOSI_LS01_R1")
		)
		(pad "2" smd circle
			(at 0.40005 0)
			(size 0 0)
			(layers "F.Cu" "F.Mask" "F.Paste")
			(net "SPI_BIC1_MOSI_LS01_R")
		)
	)
	(footprint ""
		(layer "F.Cu")
		(at 84.890864 -55.663846 90)
		(property "Reference" "PU60"
			(at -1.120394 2.791968 90)
			(unlocked yes)
			(layer "F.SilkS")
			(effects
				(font
					(size 0.7874 0.5842)
					(thickness 0.1524)
				)
				(justify left)
			)
		)
		(property "Value" ""
			(at 0 0 90)
			(layer "F.Fab")
			(effects
				(font
					(size 1.27 1.27)
				)
			)
		)
		(duplicate_pad_numbers_are_jumpers no)
		(fp_line
			(start 1.943608 -1.549908)
			(end 1.943608 1.549908)
			(stroke
				(width 0.1524)
				(type default)
			)
			(layer "F.SilkS")
		)
		(fp_line
			(start -1.943608 -1.549908)
			(end 1.943608 -1.549908)
			(stroke
				(width 0.1524)
				(type default)
			)
			(layer "F.SilkS")
		)
		(fp_line
			(start 1.943608 1.549908)
			(end -1.943608 1.549908)
			(stroke
				(width 0.1524)
				(type default)
			)
			(layer "F.SilkS")
		)
		(fp_line
			(start -1.943608 1.549908)
			(end -1.943608 -1.549908)
			(stroke
				(width 0.1524)
				(type default)
			)
			(layer "F.SilkS")
		)
		(fp_poly
			(pts
				(xy -2.019808 -1.549908) (xy -1.257808 -1.549908) (xy -1.257808 -1.880108) (xy -2.019808 -1.880108)
			)
			(stroke
				(width 0)
				(type default)
			)
			(fill yes)
			(layer "F.SilkS")
		)
		(fp_line
			(start 1.549908 -1.549908)
			(end 1.549908 1.549908)
			(stroke
				(width 0.1)
				(type default)
			)
			(layer "F.Fab")
		)
		(fp_line
			(start -1.549908 -1.549908)
			(end 1.549908 -1.549908)
			(stroke
				(width 0.1)
				(type default)
			)
			(layer "F.Fab")
		)
		(fp_line
			(start 1.549908 1.549908)
			(end -1.549908 1.549908)
			(stroke
				(width 0.1)
				(type default)
			)
			(layer "F.Fab")
		)
		(fp_line
			(start -1.549908 1.549908)
			(end -1.549908 -1.549908)
			(stroke
				(width 0.1)
				(type default)
			)
			(layer "F.Fab")
		)
		(fp_poly
			(pts
				(xy -2.019808 -1.549908) (xy -1.257808 -1.549908) (xy -1.257808 -1.880108) (xy -2.019808 -1.880108)
			)
			(stroke
				(width 0)
				(type default)
			)
			(fill yes)
			(layer "F.Fab")
		)
		(pad "1" smd rect
			(at -1.500124 -1.249934)
			(size 0.2794 0.6096)
			(layers "F.Cu" "F.Mask" "F.Paste")
			(net "P3V3_SSD3")
		)
		(pad "2" smd rect
			(at -1.500124 -0.750062)
			(size 0.2794 0.6096)
			(layers "F.Cu" "F.Mask" "F.Paste")
			(net "P3V3_SSD3")
		)
		(pad "3" smd rect
			(at -1.500124 -0.249936)
			(size 0.2794 0.6096)
			(layers "F.Cu" "F.Mask" "F.Paste")
			(net "P3V3_SSD3")
		)
		(pad "4" smd rect
			(at -1.500124 0.249936)
			(size 0.2794 0.6096)
			(layers "F.Cu" "F.Mask" "F.Paste")
			(net "P3V3_SSD3")
		)
		(pad "5" smd rect
			(at -1.500124 0.750062)
			(size 0.2794 0.6096)
			(layers "F.Cu" "F.Mask" "F.Paste")
			(net "P3V3_SSD3")
		)
		(pad "6" smd rect
			(at -1.500124 1.249934)
			(size 0.2794 0.6096)
			(layers "F.Cu" "F.Mask" "F.Paste")
			(net "GND")
		)
		(pad "7" smd rect
			(at 1.500124 1.249934)
			(size 0.2794 0.6096)
			(layers "F.Cu" "F.Mask" "F.Paste")
			(net "P3V3_SSD3_SS")
		)
		(pad "8" smd rect
			(at 1.500124 0.750062)
			(size 0.2794 0.6096)
			(layers "F.Cu" "F.Mask" "F.Paste")
			(net "PWRGD_P3V3_SSD3")
		)
		(pad "9" smd rect
			(at 1.500124 0.249936)
			(size 0.2794 0.6096)
			(layers "F.Cu" "F.Mask" "F.Paste")
			(net "P3V3_SSD3_OCP")
		)
		(pad "10" smd rect
			(at 1.500124 -0.249936)
			(size 0.2794 0.6096)
			(layers "F.Cu" "F.Mask" "F.Paste")
			(net "P5V_AUX")
		)
		(pad "11" smd rect
			(at 1.500124 -0.750062)
			(size 0.2794 0.6096)
			(layers "F.Cu" "F.Mask" "F.Paste")
			(net "SSD3_AUX_P3V3_EN_R")
		)
		(pad "12" smd rect
			(at 1.500124 -1.249934)
			(size 0.2794 0.6096)
			(layers "F.Cu" "F.Mask" "F.Paste")
			(net "P3V3_AUX")
		)
		(pad "13" smd rect
			(at 0 0 90)
			(size 1.9812 2.7178)
			(layers "F.Cu" "F.Mask" "F.Paste")
			(net "P3V3_AUX")
		)
		(zone
			(layer "F.Cu")
			(hatch none 0.5)
			(connect_pads
				(clearance 0)
			)
			(min_thickness 0.25)
			(keepout
				(tracks not_allowed)
				(vias allowed)
				(pads allowed)
				(copperpour not_allowed)
				(footprints allowed)
			)
			(placement
				(enabled no)
				(sheetname "")
			)
			(fill
				(thermal_gap 0.5)
				(thermal_bridge_width 0.5)
				(island_removal_mode 0)
			)
			(polygon
				(pts
					(xy 83.341464 -56.806846) (xy 83.468464 -56.806846) (xy 86.440264 -56.806846) (xy 86.440772 -56.806846)
					(xy 86.440772 -54.520846) (xy 86.440264 -54.520846) (xy 86.313264 -54.520846) (xy 84.890864 -54.520846)
					(xy 84.890864 -54.622446) (xy 86.313264 -54.622446) (xy 86.313264 -56.705246) (xy 83.468464 -56.705246)
					(xy 83.468464 -54.622446) (xy 84.865464 -54.622446) (xy 84.865464 -54.520846) (xy 83.468464 -54.520846)
					(xy 83.341464 -54.520846) (xy 83.340956 -54.520846) (xy 83.340956 -56.806846)
				)
			)
		)
	)
	(footprint ""
		(layer "F.Cu")
		(at 396.185644 -27.092148 -90)
		(property "Reference" "R5753"
			(at 0 0 270)
			(layer "F.SilkS")
			(hide yes)
			(effects
				(font
					(size 1.27 1.27)
				)
			)
		)
		(property "Value" ""
			(at 0 0 270)
			(layer "F.Fab")
			(effects
				(font
					(size 1.27 1.27)
				)
			)
		)
		(duplicate_pad_numbers_are_jumpers no)
		(fp_line
			(start -0.7874 0.4064)
			(end -0.7874 -0.4064)
			(stroke
				(width 0.1524)
				(type default)
			)
			(layer "F.SilkS")
		)
		(fp_line
			(start 0.7874 0.4064)
			(end -0.7874 0.4064)
			(stroke
				(width 0.1524)
				(type default)
			)
			(layer "F.SilkS")
		)
		(fp_line
			(start -0.7874 -0.4064)
			(end 0.7874 -0.4064)
			(stroke
				(width 0.1524)
				(type default)
			)
			(layer "F.SilkS")
		)
		(fp_line
			(start 0.7874 -0.4064)
			(end 0.7874 0.4064)
			(stroke
				(width 0.1524)
				(type default)
			)
			(layer "F.SilkS")
		)
		(fp_line
			(start -0.67945 0.3048)
			(end -0.67945 -0.305054)
			(stroke
				(width 0.1)
				(type default)
			)
			(layer "F.Fab")
		)
		(fp_line
			(start -0.12065 0.3048)
			(end -0.67945 0.3048)
			(stroke
				(width 0.1)
				(type default)
			)
			(layer "F.Fab")
		)
		(fp_line
			(start 0.120396 0.3048)
			(end 0.120396 0.2794)
			(stroke
				(width 0.1)
				(type default)
			)
			(layer "F.Fab")
		)
		(fp_line
			(start 0.67945 0.3048)
			(end 0.120396 0.3048)
			(stroke
				(width 0.1)
				(type default)
			)
			(layer "F.Fab")
		)
		(fp_line
			(start -0.12065 0.2794)
			(end -0.12065 0.3048)
			(stroke
				(width 0.1)
				(type default)
			)
			(layer "F.Fab")
		)
		(fp_line
			(start 0.120396 0.2794)
			(end -0.12065 0.2794)
			(stroke
				(width 0.1)
				(type default)
			)
			(layer "F.Fab")
		)
		(fp_line
			(start -0.12065 -0.2794)
			(end 0.12065 -0.2794)
			(stroke
				(width 0.1)
				(type default)
			)
			(layer "F.Fab")
		)
		(fp_line
			(start 0.12065 -0.2794)
			(end 0.12065 -0.3048)
			(stroke
				(width 0.1)
				(type default)
			)
			(layer "F.Fab")
		)
		(fp_line
			(start 0.12065 -0.3048)
			(end 0.67945 -0.3048)
			(stroke
				(width 0.1)
				(type default)
			)
			(layer "F.Fab")
		)
		(fp_line
			(start 0.67945 -0.3048)
			(end 0.67945 0.3048)
			(stroke
				(width 0.1)
				(type default)
			)
			(layer "F.Fab")
		)
		(fp_line
			(start -0.67945 -0.305054)
			(end -0.12065 -0.305054)
			(stroke
				(width 0.1)
				(type default)
			)
			(layer "F.Fab")
		)
		(fp_line
			(start -0.12065 -0.305054)
			(end -0.12065 -0.2794)
			(stroke
				(width 0.1)
				(type default)
			)
			(layer "F.Fab")
		)
		(pad "1" smd circle
			(at -0.40005 0 270)
			(size 0 0)
			(layers "F.Cu" "F.Mask" "F.Paste")
			(net "P3V3_SSD13")
		)
		(pad "2" smd circle
			(at 0.40005 0 270)
			(size 0 0)
			(layers "F.Cu" "F.Mask" "F.Paste")
			(net "SSD13_LED_ISO_N")
		)
	)
	(footprint ""
		(layer "F.Cu")
		(at 380.054358 -48.21809)
		(property "Reference" "PD71"
			(at -3.423158 2.24536 0)
			(unlocked yes)
			(layer "F.SilkS")
			(effects
				(font
					(size 0.7874 0.5842)
					(thickness 0.1524)
				)
				(justify left)
			)
		)
		(property "Value" ""
			(at 0 0 0)
			(layer "F.Fab")
			(effects
				(font
					(size 1.27 1.27)
				)
			)
		)
		(duplicate_pad_numbers_are_jumpers no)
		(fp_line
			(start -3.400044 -1.459992)
			(end 4.107942 -1.459992)
			(stroke
				(width 0.1524)
				(type default)
			)
			(layer "F.SilkS")
		)
		(fp_line
			(start -3.400044 1.459992)
			(end -3.400044 -1.459992)
			(stroke
				(width 0.1524)
				(type default)
			)
			(layer "F.SilkS")
		)
		(fp_line
			(start 4.107942 -1.459992)
			(end 4.107942 1.459992)
			(stroke
				(width 0.1524)
				(type default)
			)
			(layer "F.SilkS")
		)
		(fp_line
			(start 4.107942 1.459992)
			(end -3.400044 1.459992)
			(stroke
				(width 0.1524)
				(type default)
			)
			(layer "F.SilkS")
		)
		(fp_poly
			(pts
				(xy 4.107942 -1.459992) (xy 4.107942 1.459992) (xy 3.308096 1.459992) (xy 3.308096 -1.459992)
			)
			(stroke
				(width 0)
				(type default)
			)
			(fill yes)
			(layer "F.SilkS")
		)
		(fp_line
			(start -2.29997 -1.459992)
			(end 2.29997 -1.459992)
			(stroke
				(width 0.1)
				(type default)
			)
			(layer "F.Fab")
		)
		(fp_line
			(start -2.29997 1.459992)
			(end -2.29997 -1.459992)
			(stroke
				(width 0.1)
				(type default)
			)
			(layer "F.Fab")
		)
		(fp_line
			(start 2.29997 -1.459992)
			(end 2.29997 1.459992)
			(stroke
				(width 0.1)
				(type default)
			)
			(layer "F.Fab")
		)
		(fp_line
			(start 2.29997 1.459992)
			(end -2.29997 1.459992)
			(stroke
				(width 0.1)
				(type default)
			)
			(layer "F.Fab")
		)
		(fp_text user "+"
			(at -4.7752 -0.12065 0)
			(unlocked yes)
			(layer "F.SilkS")
			(effects
				(font
					(size 1.905 1.4224)
					(thickness 0.1524)
				)
				(justify left)
			)
		)
		(fp_text user "-"
			(at 5.4102 0.29845 180)
			(unlocked yes)
			(layer "F.SilkS")
			(effects
				(font
					(size 1.905 1.4224)
					(thickness 0.1524)
				)
				(justify left)
			)
		)
		(fp_text user "+"
			(at -4.7752 -0.12065 0)
			(unlocked yes)
			(layer "F.Fab")
			(effects
				(font
					(size 1.905 1.4224)
					(thickness 0.1524)
				)
				(justify left)
			)
		)
		(fp_text user "-"
			(at 5.4102 0.29845 180)
			(unlocked yes)
			(layer "F.Fab")
			(effects
				(font
					(size 1.905 1.4224)
					(thickness 0.1524)
				)
				(justify left)
			)
		)
		(pad "A" smd rect
			(at -1.999996 0 90)
			(size 1.7018 2.5146)
			(layers "F.Cu" "F.Mask" "F.Paste")
			(net "GND")
		)
		(pad "C" smd rect
			(at 1.999996 0 90)
			(size 1.7018 2.5146)
			(layers "F.Cu" "F.Mask" "F.Paste")
			(net "P3V3_SSD13")
		)
	)
	(footprint ""
		(layer "F.Cu")
		(at 437.250332 -356.244906 90)
		(property "Reference" "C2467"
			(at 0 0 90)
			(layer "F.SilkS")
			(hide yes)
			(effects
				(font
					(size 1.27 1.27)
				)
			)
		)
		(property "Value" ""
			(at 0 0 90)
			(layer "F.Fab")
			(effects
				(font
					(size 1.27 1.27)
				)
			)
		)
		(duplicate_pad_numbers_are_jumpers no)
		(fp_line
			(start 0.299974 -0.150114)
			(end 0.299974 0.150114)
			(stroke
				(width 0.1)
				(type default)
			)
			(layer "F.Fab")
		)
		(fp_line
			(start -0.299974 -0.150114)
			(end 0.299974 -0.150114)
			(stroke
				(width 0.1)
				(type default)
			)
			(layer "F.Fab")
		)
		(fp_line
			(start 0.299974 0.150114)
			(end -0.299974 0.150114)
			(stroke
				(width 0.1)
				(type default)
			)
			(layer "F.Fab")
		)
		(fp_line
			(start -0.299974 0.150114)
			(end -0.299974 -0.150114)
			(stroke
				(width 0.1)
				(type default)
			)
			(layer "F.Fab")
		)
		(pad "1" smd rect
			(at -0.2667 0 90)
			(size 0.3048 0.381)
			(layers "F.Cu" "F.Mask" "F.Paste")
			(net "P5E_PEX3_STN4_TX_DP<65>")
		)
		(pad "2" smd rect
			(at 0.2667 0 90)
			(size 0.3048 0.381)
			(layers "F.Cu" "F.Mask" "F.Paste")
			(net "P5E_PEX3_STN4_TX_C_DP<65>")
		)
	)
)
